FILE_TYPE = CONNECTIVITY;
{Allegro Design Entry HDL 16.6-p007 (v16-6-112F) 10/10/2012}
"PAGE_NUMBER" = 24;
0"NC";
1"M_B_DQ<63:0>";
2"M_B_CLK_DN<3:0>";
3"M_B_CLK_DP<3:0>";
4"M_B_ECC<7:0>";
5"M_B_BA<1:0>";
6"M_B_BG<1:0>";
7"M_B_CKE<3:0>";
8"M_B_CS_N<7:0>";
9"M_B_MA<17:0>";
10"M_B_ODT<3:0>";
11"M_B_DQS_DN<17:0>";
12"M_B_DQS_DP<17:0>";
13"M_B_DQS_DP<6>";
14"M_B_DQS_DP<7>";
15"M_B_DQS_DP<8>";
16"M_B_DQS_DP<9>";
17"M_B_DQS_DP<10>";
18"M_B_DQS_DP<11>";
19"M_B_DQS_DP<12>";
20"M_B_DQS_DP<13>";
21"M_B_DQS_DP<14>";
22"M_B_DQS_DP<15>";
23"M_B_DQS_DP<16>";
24"M_B_DQS_DP<17>";
25"M_B_ACT_N";
26"M_B_ALERT_N";
27"M_B_PAR";
28"M_B_MA<3>";
29"M_B_MA<4>";
30"M_B_MA<5>";
31"M_B_MA<6>";
32"M_B_MA<7>";
33"M_B_MA<8>";
34"M_B_MA<9>";
35"M_B_MA<10>";
36"M_B_MA<11>";
37"M_B_MA<12>";
38"M_B_MA<13>";
39"M_B_MA<14>";
40"M_B_MA<15>";
41"M_B_MA<16>";
42"M_B_MA<17>";
43"M_B_DQS_DP<0>";
44"M_B_DQS_DP<1>";
45"M_B_DQS_DP<2>";
46"M_B_DQS_DP<3>";
47"M_B_DQS_DP<4>";
48"M_B_DQS_DP<5>";
49"M_B_DQS_DN<0>";
50"M_B_DQS_DN<1>";
51"M_B_DQS_DN<2>";
52"M_B_DQS_DN<3>";
53"M_B_DQS_DN<4>";
54"M_B_DQS_DN<5>";
55"M_B_DQS_DN<6>";
56"M_B_DQS_DN<7>";
57"M_B_DQS_DN<8>";
58"M_B_DQS_DN<9>";
59"M_B_DQS_DN<10>";
60"M_B_DQS_DN<11>";
61"M_B_DQS_DN<12>";
62"M_B_DQS_DN<13>";
63"M_B_DQS_DN<14>";
64"M_B_DQS_DN<15>";
65"M_B_DQS_DN<16>";
66"M_B_DQS_DN<17>";
67"M_B_ODT<0>";
68"M_B_ODT<1>";
69"M_B_ODT<2>";
70"M_B_ODT<3>";
71"M_B_MA<0>";
72"M_B_MA<1>";
73"M_B_MA<2>";
74"M_B_CS_N<0>";
75"M_B_CS_N<1>";
76"M_B_CS_N<2>";
77"M_B_CS_N<3>";
78"M_B_CS_N<4>";
79"M_B_CS_N<5>";
80"M_B_CS_N<6>";
81"M_B_CS_N<7>";
82"M_B_CKE<0>";
83"M_B_CKE<1>";
84"M_B_CKE<2>";
85"M_B_CKE<3>";
86"M_B_BG<0>";
87"M_B_BG<1>";
88"M_B_BA<0>";
89"M_B_BA<1>";
90"M_B_DQ<52>";
91"M_B_DQ<53>";
92"M_B_DQ<54>";
93"M_B_DQ<55>";
94"M_B_DQ<56>";
95"M_B_DQ<57>";
96"M_B_DQ<58>";
97"M_B_DQ<59>";
98"M_B_DQ<60>";
99"M_B_DQ<61>";
100"M_B_DQ<62>";
101"M_B_DQ<63>";
102"M_B_DQ<11>";
103"M_B_DQ<12>";
104"M_B_DQ<13>";
105"M_B_DQ<14>";
106"M_B_DQ<15>";
107"M_B_DQ<16>";
108"M_B_DQ<17>";
109"M_B_DQ<18>";
110"M_B_DQ<19>";
111"M_B_DQ<20>";
112"M_B_DQ<21>";
113"M_B_DQ<22>";
114"M_B_DQ<23>";
115"M_B_DQ<24>";
116"M_B_DQ<25>";
117"M_B_DQ<26>";
118"M_B_DQ<27>";
119"M_B_DQ<28>";
120"M_B_DQ<29>";
121"M_B_DQ<30>";
122"M_B_DQ<31>";
123"M_B_DQ<32>";
124"M_B_DQ<33>";
125"M_B_DQ<34>";
126"M_B_DQ<35>";
127"M_B_DQ<36>";
128"M_B_DQ<37>";
129"M_B_DQ<38>";
130"M_B_DQ<39>";
131"M_B_DQ<40>";
132"M_B_DQ<41>";
133"M_B_DQ<42>";
134"M_B_DQ<43>";
135"M_B_DQ<44>";
136"M_B_DQ<45>";
137"M_B_DQ<46>";
138"M_B_DQ<47>";
139"M_B_DQ<48>";
140"M_B_DQ<49>";
141"M_B_DQ<50>";
142"M_B_DQ<51>";
143"M_B_ECC<0>";
144"M_B_ECC<1>";
145"M_B_ECC<2>";
146"M_B_ECC<3>";
147"M_B_ECC<4>";
148"M_B_ECC<5>";
149"M_B_ECC<6>";
150"M_B_ECC<7>";
151"M_B_DQ<0>";
152"M_B_DQ<1>";
153"M_B_DQ<2>";
154"M_B_DQ<3>";
155"M_B_DQ<4>";
156"M_B_DQ<6>";
157"M_B_DQ<7>";
158"M_B_DQ<8>";
159"M_B_DQ<9>";
160"M_B_DQ<10>";
161"M_B_CLK_DP<0>";
162"M_B_CLK_DP<1>";
163"M_B_CLK_DP<2>";
164"M_B_CLK_DP<3>";
165"M_B_CLK_DN<0>";
166"M_B_CLK_DN<1>";
167"M_B_CLK_DN<2>";
168"M_B_CLK_DN<3>";
169"M_B_C<2>";
170"M_B_DQ<5>";
%"TAP"
"6","(-5525,750)","0","mstr_standard","I10";
;
HDL_TAP"TRUE"
BODY_TYPE"PLUMBING"
CDS_LIB"mstr_standard";
"B \NAC \NWC"2;
"S \NAC"
BN"3"168;
%"TAP"
"6","(-2800,1550)","2","mstr_standard","I100";
;
HDL_TAP"TRUE"
BODY_TYPE"PLUMBING"
CDS_LIB"mstr_standard";
"B \NAC \NWC"10;
"S \NAC"
BN"3"70;
%"TAP"
"6","(-2800,1450)","2","mstr_standard","I101";
;
HDL_TAP"TRUE"
BODY_TYPE"PLUMBING"
CDS_LIB"mstr_standard";
"B \NAC \NWC"10;
"S \NAC"
BN"1"68;
%"TAP"
"6","(-2800,1650)","2","mstr_standard","I102";
;
HDL_TAP"TRUE"
BODY_TYPE"PLUMBING"
CDS_LIB"mstr_standard";
"B \NAC \NWC"7;
"S \NAC"
BN"0"82;
%"TAP"
"6","(-2800,1500)","2","mstr_standard","I103";
;
HDL_TAP"TRUE"
BODY_TYPE"PLUMBING"
CDS_LIB"mstr_standard";
"B \NAC \NWC"10;
"S \NAC"
BN"2"69;
%"TAP"
"6","(-2800,1750)","2","mstr_standard","I104";
;
HDL_TAP"TRUE"
BODY_TYPE"PLUMBING"
CDS_LIB"mstr_standard";
"B \NAC \NWC"7;
"S \NAC"
BN"2"84;
%"TAP"
"6","(-2800,1700)","2","mstr_standard","I105";
;
HDL_TAP"TRUE"
BODY_TYPE"PLUMBING"
CDS_LIB"mstr_standard";
"B \NAC \NWC"7;
"S \NAC"
BN"1"83;
%"TAP"
"6","(-2800,1900)","2","mstr_standard","I106";
;
HDL_TAP"TRUE"
BODY_TYPE"PLUMBING"
CDS_LIB"mstr_standard";
"B \NAC \NWC"9;
"S \NAC"
BN"0"71;
%"TAP"
"6","(-2800,1800)","2","mstr_standard","I107";
;
HDL_TAP"TRUE"
BODY_TYPE"PLUMBING"
CDS_LIB"mstr_standard";
"B \NAC \NWC"7;
"S \NAC"
BN"3"85;
%"TAP"
"6","(-2800,2100)","2","mstr_standard","I108";
;
HDL_TAP"TRUE"
BODY_TYPE"PLUMBING"
CDS_LIB"mstr_standard";
"B \NAC \NWC"9;
"S \NAC"
BN"4"29;
%"TAP"
"6","(-2800,2150)","2","mstr_standard","I109";
;
HDL_TAP"TRUE"
BODY_TYPE"PLUMBING"
CDS_LIB"mstr_standard";
"B \NAC \NWC"9;
"S \NAC"
BN"5"30;
%"TAP"
"6","(-5525,900)","0","mstr_standard","I11";
;
HDL_TAP"TRUE"
BODY_TYPE"PLUMBING"
CDS_LIB"mstr_standard";
"B \NAC \NWC"3;
"S \NAC"
BN"2"163;
%"TAP"
"6","(-2800,2000)","2","mstr_standard","I110";
;
HDL_TAP"TRUE"
BODY_TYPE"PLUMBING"
CDS_LIB"mstr_standard";
"B \NAC \NWC"9;
"S \NAC"
BN"2"73;
%"TAP"
"6","(-2800,2050)","2","mstr_standard","I111";
;
HDL_TAP"TRUE"
BODY_TYPE"PLUMBING"
CDS_LIB"mstr_standard";
"B \NAC \NWC"9;
"S \NAC"
BN"3"28;
%"TAP"
"6","(-2800,1950)","2","mstr_standard","I112";
;
HDL_TAP"TRUE"
BODY_TYPE"PLUMBING"
CDS_LIB"mstr_standard";
"B \NAC \NWC"9;
"S \NAC"
BN"1"72;
%"TAP"
"6","(-2800,2400)","2","mstr_standard","I113";
;
HDL_TAP"TRUE"
BODY_TYPE"PLUMBING"
CDS_LIB"mstr_standard";
"B \NAC \NWC"9;
"S \NAC"
BN"10"35;
%"TAP"
"6","(-2800,2350)","2","mstr_standard","I114";
;
HDL_TAP"TRUE"
BODY_TYPE"PLUMBING"
CDS_LIB"mstr_standard";
"B \NAC \NWC"9;
"S \NAC"
BN"9"34;
%"TAP"
"6","(-2800,2300)","2","mstr_standard","I115";
;
HDL_TAP"TRUE"
BODY_TYPE"PLUMBING"
CDS_LIB"mstr_standard";
"B \NAC \NWC"9;
"S \NAC"
BN"8"33;
%"TAP"
"6","(-2800,2250)","2","mstr_standard","I116";
;
HDL_TAP"TRUE"
BODY_TYPE"PLUMBING"
CDS_LIB"mstr_standard";
"B \NAC \NWC"9;
"S \NAC"
BN"7"32;
%"TAP"
"6","(-2800,2200)","2","mstr_standard","I117";
;
HDL_TAP"TRUE"
BODY_TYPE"PLUMBING"
CDS_LIB"mstr_standard";
"B \NAC \NWC"9;
"S \NAC"
BN"6"31;
%"TAP"
"6","(-2800,2650)","2","mstr_standard","I118";
;
HDL_TAP"TRUE"
BODY_TYPE"PLUMBING"
CDS_LIB"mstr_standard";
"B \NAC \NWC"9;
"S \NAC"
BN"15"40;
%"TAP"
"6","(-2800,2600)","2","mstr_standard","I119";
;
HDL_TAP"TRUE"
BODY_TYPE"PLUMBING"
CDS_LIB"mstr_standard";
"B \NAC \NWC"9;
"S \NAC"
BN"14"39;
%"TAP"
"6","(-5525,950)","0","mstr_standard","I12";
;
HDL_TAP"TRUE"
BODY_TYPE"PLUMBING"
CDS_LIB"mstr_standard";
"B \NAC \NWC"3;
"S \NAC"
BN"3"164;
%"TAP"
"6","(-2800,2550)","2","mstr_standard","I120";
;
HDL_TAP"TRUE"
BODY_TYPE"PLUMBING"
CDS_LIB"mstr_standard";
"B \NAC \NWC"9;
"S \NAC"
BN"13"38;
%"TAP"
"6","(-2800,2500)","2","mstr_standard","I121";
;
HDL_TAP"TRUE"
BODY_TYPE"PLUMBING"
CDS_LIB"mstr_standard";
"B \NAC \NWC"9;
"S \NAC"
BN"12"37;
%"TAP"
"6","(-2800,2450)","2","mstr_standard","I122";
;
HDL_TAP"TRUE"
BODY_TYPE"PLUMBING"
CDS_LIB"mstr_standard";
"B \NAC \NWC"9;
"S \NAC"
BN"11"36;
%"TAP"
"6","(-2800,2850)","2","mstr_standard","I123";
;
HDL_TAP"TRUE"
BODY_TYPE"PLUMBING"
CDS_LIB"mstr_standard";
"B \NAC \NWC"11;
"S \NAC"
BN"0"49;
%"TAP"
"6","(-2800,2900)","2","mstr_standard","I124";
;
HDL_TAP"TRUE"
BODY_TYPE"PLUMBING"
CDS_LIB"mstr_standard";
"B \NAC \NWC"11;
"S \NAC"
BN"1"50;
%"TAP"
"6","(-2800,2750)","2","mstr_standard","I125";
;
HDL_TAP"TRUE"
BODY_TYPE"PLUMBING"
CDS_LIB"mstr_standard";
"B \NAC \NWC"9;
"S \NAC"
BN"17"42;
%"TAP"
"6","(-2800,2700)","2","mstr_standard","I126";
;
HDL_TAP"TRUE"
BODY_TYPE"PLUMBING"
CDS_LIB"mstr_standard";
"B \NAC \NWC"9;
"S \NAC"
BN"16"41;
%"TAP"
"6","(-2800,2950)","2","mstr_standard","I127";
;
HDL_TAP"TRUE"
BODY_TYPE"PLUMBING"
CDS_LIB"mstr_standard";
"B \NAC \NWC"11;
"S \NAC"
BN"2"51;
%"TAP"
"6","(-2800,3000)","2","mstr_standard","I128";
;
HDL_TAP"TRUE"
BODY_TYPE"PLUMBING"
CDS_LIB"mstr_standard";
"B \NAC \NWC"11;
"S \NAC"
BN"3"52;
%"TAP"
"6","(-2800,3050)","2","mstr_standard","I129";
;
HDL_TAP"TRUE"
BODY_TYPE"PLUMBING"
CDS_LIB"mstr_standard";
"B \NAC \NWC"11;
"S \NAC"
BN"4"53;
%"TAP"
"6","(-5525,1050)","0","mstr_standard","I13";
;
HDL_TAP"TRUE"
BODY_TYPE"PLUMBING"
CDS_LIB"mstr_standard";
"B \NAC \NWC"4;
"S \NAC"
BN"0"143;
%"TAP"
"6","(-2800,3150)","2","mstr_standard","I130";
;
HDL_TAP"TRUE"
BODY_TYPE"PLUMBING"
CDS_LIB"mstr_standard";
"B \NAC \NWC"11;
"S \NAC"
BN"6"55;
%"TAP"
"6","(-2800,3200)","2","mstr_standard","I131";
;
HDL_TAP"TRUE"
BODY_TYPE"PLUMBING"
CDS_LIB"mstr_standard";
"B \NAC \NWC"11;
"S \NAC"
BN"7"56;
%"TAP"
"6","(-2800,3100)","2","mstr_standard","I132";
;
HDL_TAP"TRUE"
BODY_TYPE"PLUMBING"
CDS_LIB"mstr_standard";
"B \NAC \NWC"11;
"S \NAC"
BN"5"54;
%"TAP"
"6","(-2800,3250)","2","mstr_standard","I133";
;
HDL_TAP"TRUE"
BODY_TYPE"PLUMBING"
CDS_LIB"mstr_standard";
"B \NAC \NWC"11;
"S \NAC"
BN"8"57;
%"TAP"
"6","(-2800,3450)","2","mstr_standard","I134";
;
HDL_TAP"TRUE"
BODY_TYPE"PLUMBING"
CDS_LIB"mstr_standard";
"B \NAC \NWC"11;
"S \NAC"
BN"12"61;
%"TAP"
"6","(-2800,3400)","2","mstr_standard","I135";
;
HDL_TAP"TRUE"
BODY_TYPE"PLUMBING"
CDS_LIB"mstr_standard";
"B \NAC \NWC"11;
"S \NAC"
BN"11"60;
%"TAP"
"6","(-2800,3300)","2","mstr_standard","I136";
;
HDL_TAP"TRUE"
BODY_TYPE"PLUMBING"
CDS_LIB"mstr_standard";
"B \NAC \NWC"11;
"S \NAC"
BN"9"58;
%"TAP"
"6","(-2800,3350)","2","mstr_standard","I137";
;
HDL_TAP"TRUE"
BODY_TYPE"PLUMBING"
CDS_LIB"mstr_standard";
"B \NAC \NWC"11;
"S \NAC"
BN"10"59;
%"TAP"
"6","(-2800,3500)","2","mstr_standard","I138";
;
HDL_TAP"TRUE"
BODY_TYPE"PLUMBING"
CDS_LIB"mstr_standard";
"B \NAC \NWC"11;
"S \NAC"
BN"13"62;
%"TAP"
"6","(-2800,3700)","2","mstr_standard","I139";
;
HDL_TAP"TRUE"
BODY_TYPE"PLUMBING"
CDS_LIB"mstr_standard";
"B \NAC \NWC"11;
"S \NAC"
BN"17"66;
%"TAP"
"6","(-5525,1100)","0","mstr_standard","I14";
;
HDL_TAP"TRUE"
BODY_TYPE"PLUMBING"
CDS_LIB"mstr_standard";
"B \NAC \NWC"4;
"S \NAC"
BN"1"144;
%"TAP"
"6","(-2800,3650)","2","mstr_standard","I140";
;
HDL_TAP"TRUE"
BODY_TYPE"PLUMBING"
CDS_LIB"mstr_standard";
"B \NAC \NWC"11;
"S \NAC"
BN"16"65;
%"TAP"
"6","(-2800,3600)","2","mstr_standard","I141";
;
HDL_TAP"TRUE"
BODY_TYPE"PLUMBING"
CDS_LIB"mstr_standard";
"B \NAC \NWC"11;
"S \NAC"
BN"15"64;
%"TAP"
"6","(-2800,3550)","2","mstr_standard","I142";
;
HDL_TAP"TRUE"
BODY_TYPE"PLUMBING"
CDS_LIB"mstr_standard";
"B \NAC \NWC"11;
"S \NAC"
BN"14"63;
%"TAP"
"6","(-2800,3800)","2","mstr_standard","I143";
;
HDL_TAP"TRUE"
BODY_TYPE"PLUMBING"
CDS_LIB"mstr_standard";
"B \NAC \NWC"12;
"S \NAC"
BN"0"43;
%"TAP"
"6","(-2800,3900)","2","mstr_standard","I144";
;
HDL_TAP"TRUE"
BODY_TYPE"PLUMBING"
CDS_LIB"mstr_standard";
"B \NAC \NWC"12;
"S \NAC"
BN"2"45;
%"TAP"
"6","(-2800,3950)","2","mstr_standard","I145";
;
HDL_TAP"TRUE"
BODY_TYPE"PLUMBING"
CDS_LIB"mstr_standard";
"B \NAC \NWC"12;
"S \NAC"
BN"3"46;
%"TAP"
"6","(-2800,3850)","2","mstr_standard","I146";
;
HDL_TAP"TRUE"
BODY_TYPE"PLUMBING"
CDS_LIB"mstr_standard";
"B \NAC \NWC"12;
"S \NAC"
BN"1"44;
%"TAP"
"6","(-5525,1150)","0","mstr_standard","I15";
;
HDL_TAP"TRUE"
BODY_TYPE"PLUMBING"
CDS_LIB"mstr_standard";
"B \NAC \NWC"4;
"S \NAC"
BN"2"145;
%"TAP"
"6","(-2800,4150)","2","mstr_standard","I157";
;
HDL_TAP"TRUE"
BODY_TYPE"PLUMBING"
CDS_LIB"mstr_standard";
"B \NAC \NWC"12;
"S \NAC"
BN"7"14;
%"TAP"
"6","(-2800,4200)","2","mstr_standard","I158";
;
HDL_TAP"TRUE"
BODY_TYPE"PLUMBING"
CDS_LIB"mstr_standard";
"B \NAC \NWC"12;
"S \NAC"
BN"8"15;
%"TAP"
"6","(-2800,4050)","2","mstr_standard","I159";
;
HDL_TAP"TRUE"
BODY_TYPE"PLUMBING"
CDS_LIB"mstr_standard";
"B \NAC \NWC"12;
"S \NAC"
BN"5"48;
%"TAP"
"6","(-5525,1250)","0","mstr_standard","I16";
;
HDL_TAP"TRUE"
BODY_TYPE"PLUMBING"
CDS_LIB"mstr_standard";
"B \NAC \NWC"4;
"S \NAC"
BN"4"147;
%"TAP"
"6","(-2800,4100)","2","mstr_standard","I160";
;
HDL_TAP"TRUE"
BODY_TYPE"PLUMBING"
CDS_LIB"mstr_standard";
"B \NAC \NWC"12;
"S \NAC"
BN"6"13;
%"TAP"
"6","(-2800,4000)","2","mstr_standard","I161";
;
HDL_TAP"TRUE"
BODY_TYPE"PLUMBING"
CDS_LIB"mstr_standard";
"B \NAC \NWC"12;
"S \NAC"
BN"4"47;
%"TAP"
"6","(-2800,4450)","2","mstr_standard","I162";
;
HDL_TAP"TRUE"
BODY_TYPE"PLUMBING"
CDS_LIB"mstr_standard";
"B \NAC \NWC"12;
"S \NAC"
BN"13"20;
%"TAP"
"6","(-2800,4400)","2","mstr_standard","I163";
;
HDL_TAP"TRUE"
BODY_TYPE"PLUMBING"
CDS_LIB"mstr_standard";
"B \NAC \NWC"12;
"S \NAC"
BN"12"19;
%"TAP"
"6","(-2800,4350)","2","mstr_standard","I164";
;
HDL_TAP"TRUE"
BODY_TYPE"PLUMBING"
CDS_LIB"mstr_standard";
"B \NAC \NWC"12;
"S \NAC"
BN"11"18;
%"TAP"
"6","(-2800,4300)","2","mstr_standard","I165";
;
HDL_TAP"TRUE"
BODY_TYPE"PLUMBING"
CDS_LIB"mstr_standard";
"B \NAC \NWC"12;
"S \NAC"
BN"10"17;
%"TAP"
"6","(-2800,4250)","2","mstr_standard","I166";
;
HDL_TAP"TRUE"
BODY_TYPE"PLUMBING"
CDS_LIB"mstr_standard";
"B \NAC \NWC"12;
"S \NAC"
BN"9"16;
%"TAP"
"6","(-2800,4600)","2","mstr_standard","I167";
;
HDL_TAP"TRUE"
BODY_TYPE"PLUMBING"
CDS_LIB"mstr_standard";
"B \NAC \NWC"12;
"S \NAC"
BN"16"23;
%"TAP"
"6","(-2800,4650)","2","mstr_standard","I168";
;
HDL_TAP"TRUE"
BODY_TYPE"PLUMBING"
CDS_LIB"mstr_standard";
"B \NAC \NWC"12;
"S \NAC"
BN"17"24;
%"TAP"
"6","(-2800,4550)","2","mstr_standard","I169";
;
HDL_TAP"TRUE"
BODY_TYPE"PLUMBING"
CDS_LIB"mstr_standard";
"B \NAC \NWC"12;
"S \NAC"
BN"15"22;
%"TAP"
"6","(-5525,1200)","0","mstr_standard","I17";
;
HDL_TAP"TRUE"
BODY_TYPE"PLUMBING"
CDS_LIB"mstr_standard";
"B \NAC \NWC"4;
"S \NAC"
BN"3"146;
%"TAP"
"6","(-2800,4500)","2","mstr_standard","I170";
;
HDL_TAP"TRUE"
BODY_TYPE"PLUMBING"
CDS_LIB"mstr_standard";
"B \NAC \NWC"12;
"S \NAC"
BN"14"21;
%"SKX_EXT_B"
"4","(-4125,2550)","0","chpset_lib","I172";
;
CDS_SEC"4"
ROOM"CPU0"
CDS_LOCATION"U5D1"
SEC"4"
CDS_LIB"chpset_lib"
SEC_TYPE"BGA1"
PACK_TYPE"BGA1"
MATERIAL"IC"
PART_NUMBER"TBD"
LOCATION"U5D1";
"DDR1_PAR"
$PN"K53"27;
"DDR1_ODT<0>"
$PN"N50"67;
"DDR1_ODT<1>"
$PN"R48"68;
"DDR1_ODT<2>"
$PN"M49"69;
"DDR1_ODT<3>"
$PN"T47"70;
"DDR1_MA<0>"
$PN"J52"71;
"DDR1_MA<1>"
$PN"J58"72;
"DDR1_MA<2>"
$PN"K57"73;
"DDR1_MA<3>"
$PN"N58"28;
"DDR1_MA<4>"
$PN"M59"29;
"DDR1_MA<5>"
$PN"R58"30;
"DDR1_MA<6>"
$PN"T59"31;
"DDR1_MA<7>"
$PN"V61"32;
"DDR1_MA<8>"
$PN"W60"33;
"DDR1_MA<9>"
$PN"K59"34;
"DDR1_MA<10>"
$PN"M55"35;
"DDR1_MA<11>"
$PN"R60"36;
"DDR1_MA<12>"
$PN"T61"37;
"DDR1_MA<13>"
$PN"M51"38;
"DDR1_MA<14>"
$PN"T51"39;
"DDR1_MA<15>"
$PN"N52"40;
"DDR1_MA<16>"
$PN"R52"41;
"DDR1_MA<17>"
$PN"N48"42;
"DDR1_ECC<0>"
$PN"J70"143;
"DDR1_ECC<1>"
$PN"H69"144;
"DDR1_ECC<2>"
$PN"J66"145;
"DDR1_ECC<3>"
$PN"L66"146;
"DDR1_ECC<4>"
$PN"L70"147;
"DDR1_ECC<5>"
$PN"M69"148;
"DDR1_ECC<6>"
$PN"H67"149;
"DDR1_ECC<7>"
$PN"M67"150;
"DDR1_DQS_DP<0>"
$PN"AR80"43;
"DDR1_DQS_DP<1>"
$PN"AE80"44;
"DDR1_DQS_DP<2>"
$PN"H79"45;
"DDR1_DQS_DP<3>"
$PN"F73"46;
"DDR1_DQS_DP<4>"
$PN"R42"47;
"DDR1_DQS_DP<5>"
$PN"E34"48;
"DDR1_DQS_DP<6>"
$PN"E28"13;
"DDR1_DQS_DP<7>"
$PN"Y27"14;
"DDR1_DQS_DP<8>"
$PN"L68"15;
"DDR1_DQS_DP<9>"
$PN"AT81"16;
"DDR1_DQS_DP<10>"
$PN"AF81"17;
"DDR1_DQS_DP<11>"
$PN"F79"18;
"DDR1_DQS_DP<12>"
$PN"D73"19;
"DDR1_DQS_DP<13>"
$PN"L42"20;
"DDR1_DQS_DP<14>"
$PN"C34"21;
"DDR1_DQS_DP<15>"
$PN"C28"22;
"DDR1_DQS_DP<16>"
$PN"V27"23;
"DDR1_DQS_DP<17>"
$PN"J68"24;
"DDR1_DQS_DN<0>"
$PN"AP79"49;
"DDR1_DQS_DN<1>"
$PN"AD79"50;
"DDR1_DQS_DN<2>"
$PN"K79"51;
"DDR1_DQS_DN<3>"
$PN"H73"52;
"DDR1_DQS_DN<4>"
$PN"N42"53;
"DDR1_DQS_DN<5>"
$PN"G34"54;
"DDR1_DQS_DN<6>"
$PN"G28"55;
"DDR1_DQS_DN<7>"
$PN"AB27"56;
"DDR1_DQS_DN<8>"
$PN"N68"57;
"DDR1_DQS_DN<9>"
$PN"AU82"58;
"DDR1_DQS_DN<10>"
$PN"AG82"59;
"DDR1_DQS_DN<11>"
$PN"D79"60;
"DDR1_DQS_DN<12>"
$PN"B73"61;
"DDR1_DQS_DN<13>"
$PN"J42"62;
"DDR1_DQS_DN<14>"
$PN"A34"63;
"DDR1_DQS_DN<15>"
$PN"A28"64;
"DDR1_DQS_DN<16>"
$PN"T27"65;
"DDR1_DQS_DN<17>"
$PN"G68"66;
"DDR1_DQ<0>"
$PN"AV81"151;
"DDR1_DQ<1>"
$PN"AT79"152;
"DDR1_DQ<2>"
$PN"AN82"153;
"DDR1_DQ<3>"
$PN"AM81"154;
"DDR1_DQ<4>"
$PN"AW80"155;
"DDR1_DQ<5>"
$PN"AV79"170;
"DDR1_DQ<6>"
$PN"AR82"156;
"DDR1_DQ<7>"
$PN"AN80"157;
"DDR1_DQ<8>"
$PN"AH81"158;
"DDR1_DQ<9>"
$PN"AF79"159;
"DDR1_DQ<10>"
$PN"AC82"160;
"DDR1_DQ<11>"
$PN"AB81"102;
"DDR1_DQ<12>"
$PN"AJ80"103;
"DDR1_DQ<13>"
$PN"AH79"104;
"DDR1_DQ<14>"
$PN"AE82"105;
"DDR1_DQ<15>"
$PN"AC80"106;
"DDR1_DQ<16>"
$PN"E80"107;
"DDR1_DQ<17>"
$PN"J80"108;
"DDR1_DQ<18>"
$PN"F77"109;
"DDR1_DQ<19>"
$PN"H77"110;
"DDR1_DQ<20>"
$PN"F81"111;
"DDR1_DQ<21>"
$PN"H81"112;
"DDR1_DQ<22>"
$PN"E78"113;
"DDR1_DQ<23>"
$PN"J78"114;
"DDR1_DQ<24>"
$PN"D75"115;
"DDR1_DQ<25>"
$PN"C74"116;
"DDR1_DQ<26>"
$PN"D71"117;
"DDR1_DQ<27>"
$PN"F71"118;
"DDR1_DQ<28>"
$PN"F75"119;
"DDR1_DQ<29>"
$PN"G74"120;
"DDR1_DQ<30>"
$PN"C72"121;
"DDR1_DQ<31>"
$PN"G72"122;
"DDR1_DQ<32>"
$PN"K43"123;
"DDR1_DQ<33>"
$PN"H43"124;
"DDR1_DQ<34>"
$PN"L40"125;
"DDR1_DQ<35>"
$PN"N40"126;
"DDR1_DQ<36>"
$PN"P43"127;
"DDR1_DQ<37>"
$PN"T43"128;
"DDR1_DQ<38>"
$PN"K41"129;
"DDR1_DQ<39>"
$PN"P41"130;
"DDR1_DQ<40>"
$PN"C36"131;
"DDR1_DQ<41>"
$PN"B35"132;
"DDR1_DQ<42>"
$PN"C32"133;
"DDR1_DQ<43>"
$PN"E32"134;
"DDR1_DQ<44>"
$PN"E36"135;
"DDR1_DQ<45>"
$PN"F35"136;
"DDR1_DQ<46>"
$PN"B33"137;
"DDR1_DQ<47>"
$PN"F33"138;
"DDR1_DQ<48>"
$PN"C30"139;
"DDR1_DQ<49>"
$PN"B29"140;
"DDR1_DQ<50>"
$PN"C26"141;
"DDR1_DQ<51>"
$PN"E26"142;
"DDR1_DQ<52>"
$PN"E30"90;
"DDR1_DQ<53>"
$PN"F29"91;
"DDR1_DQ<54>"
$PN"B27"92;
"DDR1_DQ<55>"
$PN"F27"93;
"DDR1_DQ<56>"
$PN"U28"94;
"DDR1_DQ<57>"
$PN"AA28"95;
"DDR1_DQ<58>"
$PN"V25"96;
"DDR1_DQ<59>"
$PN"Y25"97;
"DDR1_DQ<60>"
$PN"V29"98;
"DDR1_DQ<61>"
$PN"Y29"99;
"DDR1_DQ<62>"
$PN"U26"100;
"DDR1_DQ<63>"
$PN"AA26"101;
"DDR1_CS_N<0>"
$PN"K51"74;
"DDR1_CS_N<1>"
$PN"R50"75;
"DDR1_CS_N<2>"
$PN"N46"76;
"DDR1_CS_N<3>"
$PN"V47"77;
"DDR1_CS_N<4>"
$PN"J50"78;
"DDR1_CS_N<5>"
$PN"T49"79;
"DDR1_CS_N<6>"
$PN"M45"80;
"DDR1_CS_N<7>"
$PN"R46"81;
"DDR1_CLK_DP<0>"
$PN"N54"161;
"DDR1_CLK_DP<1>"
$PN"T55"162;
"DDR1_CLK_DP<2>"
$PN"M57"163;
"DDR1_CLK_DP<3>"
$PN"T57"164;
"DDR1_CLK_DN<0>"
$PN"M53"165;
"DDR1_CLK_DN<1>"
$PN"R54"166;
"DDR1_CLK_DN<2>"
$PN"N56"167;
"DDR1_CLK_DN<3>"
$PN"R56"168;
"DDR1_CKE<0>"
$PN"N62"82;
"DDR1_CKE<1>"
$PN"R64"83;
"DDR1_CKE<2>"
$PN"K63"84;
"DDR1_CKE<3>"
$PN"L64"85;
"DDR1_CID<2>"
$PN"M47"169;
"DDR1_BG<0>"
$PN"M61"86;
"DDR1_BG<1>"
$PN"N60"87;
"DDR1_BA<0>"
$PN"T53"88;
"DDR1_BA<1>"
$PN"K55"89;
"DDR1_ALERT_N"
$PN"W62"26;
"DDR1_ACT_N"
$PN"T63"25;
%"TAP"
"6","(-5525,1300)","0","mstr_standard","I18";
;
HDL_TAP"TRUE"
BODY_TYPE"PLUMBING"
CDS_LIB"mstr_standard";
"B \NAC \NWC"4;
"S \NAC"
BN"5"148;
%"TAP"
"6","(-5525,1350)","0","mstr_standard","I19";
;
HDL_TAP"TRUE"
BODY_TYPE"PLUMBING"
CDS_LIB"mstr_standard";
"B \NAC \NWC"4;
"S \NAC"
BN"6"149;
%"TAP"
"6","(-5525,1400)","0","mstr_standard","I20";
;
HDL_TAP"TRUE"
BODY_TYPE"PLUMBING"
CDS_LIB"mstr_standard";
"B \NAC \NWC"4;
"S \NAC"
BN"7"150;
%"TAP"
"6","(-5525,1500)","0","mstr_standard","I21";
;
HDL_TAP"TRUE"
BODY_TYPE"PLUMBING"
CDS_LIB"mstr_standard";
"B \NAC \NWC"1;
"S \NAC"
BN"0"151;
%"TAP"
"6","(-5525,1550)","0","mstr_standard","I22";
;
HDL_TAP"TRUE"
BODY_TYPE"PLUMBING"
CDS_LIB"mstr_standard";
"B \NAC \NWC"1;
"S \NAC"
BN"1"152;
%"TAP"
"6","(-5525,1600)","0","mstr_standard","I23";
;
HDL_TAP"TRUE"
BODY_TYPE"PLUMBING"
CDS_LIB"mstr_standard";
"B \NAC \NWC"1;
"S \NAC"
BN"2"153;
%"TAP"
"6","(-5525,1650)","0","mstr_standard","I24";
;
HDL_TAP"TRUE"
BODY_TYPE"PLUMBING"
CDS_LIB"mstr_standard";
"B \NAC \NWC"1;
"S \NAC"
BN"3"154;
%"TAP"
"6","(-5525,1700)","0","mstr_standard","I25";
;
HDL_TAP"TRUE"
BODY_TYPE"PLUMBING"
CDS_LIB"mstr_standard";
"B \NAC \NWC"1;
"S \NAC"
BN"4"155;
%"TAP"
"6","(-5525,1750)","0","mstr_standard","I26";
;
HDL_TAP"TRUE"
BODY_TYPE"PLUMBING"
CDS_LIB"mstr_standard";
"B \NAC \NWC"1;
"S \NAC"
BN"5"170;
%"TAP"
"6","(-5525,1800)","0","mstr_standard","I27";
;
HDL_TAP"TRUE"
BODY_TYPE"PLUMBING"
CDS_LIB"mstr_standard";
"B \NAC \NWC"1;
"S \NAC"
BN"6"156;
%"TAP"
"6","(-5525,1850)","0","mstr_standard","I28";
;
HDL_TAP"TRUE"
BODY_TYPE"PLUMBING"
CDS_LIB"mstr_standard";
"B \NAC \NWC"1;
"S \NAC"
BN"7"157;
%"TAP"
"6","(-5525,1900)","0","mstr_standard","I29";
;
HDL_TAP"TRUE"
BODY_TYPE"PLUMBING"
CDS_LIB"mstr_standard";
"B \NAC \NWC"1;
"S \NAC"
BN"8"158;
%"TAP"
"6","(-5525,2000)","0","mstr_standard","I31";
;
HDL_TAP"TRUE"
BODY_TYPE"PLUMBING"
CDS_LIB"mstr_standard";
"B \NAC \NWC"1;
"S \NAC"
BN"10"160;
%"TAP"
"6","(-5525,1950)","0","mstr_standard","I32";
;
HDL_TAP"TRUE"
BODY_TYPE"PLUMBING"
CDS_LIB"mstr_standard";
"B \NAC \NWC"1;
"S \NAC"
BN"9"159;
%"TAP"
"6","(-5525,2100)","0","mstr_standard","I33";
;
HDL_TAP"TRUE"
BODY_TYPE"PLUMBING"
CDS_LIB"mstr_standard";
"B \NAC \NWC"1;
"S \NAC"
BN"12"103;
%"TAP"
"6","(-5525,2150)","0","mstr_standard","I34";
;
HDL_TAP"TRUE"
BODY_TYPE"PLUMBING"
CDS_LIB"mstr_standard";
"B \NAC \NWC"1;
"S \NAC"
BN"13"104;
%"TAP"
"6","(-5525,2050)","0","mstr_standard","I35";
;
HDL_TAP"TRUE"
BODY_TYPE"PLUMBING"
CDS_LIB"mstr_standard";
"B \NAC \NWC"1;
"S \NAC"
BN"11"102;
%"TAP"
"6","(-5525,2200)","0","mstr_standard","I36";
;
HDL_TAP"TRUE"
BODY_TYPE"PLUMBING"
CDS_LIB"mstr_standard";
"B \NAC \NWC"1;
"S \NAC"
BN"14"105;
%"TAP"
"6","(-5525,2250)","0","mstr_standard","I37";
;
HDL_TAP"TRUE"
BODY_TYPE"PLUMBING"
CDS_LIB"mstr_standard";
"B \NAC \NWC"1;
"S \NAC"
BN"15"106;
%"TAP"
"6","(-5525,2300)","0","mstr_standard","I38";
;
HDL_TAP"TRUE"
BODY_TYPE"PLUMBING"
CDS_LIB"mstr_standard";
"B \NAC \NWC"1;
"S \NAC"
BN"16"107;
%"TAP"
"6","(-5525,2350)","0","mstr_standard","I39";
;
HDL_TAP"TRUE"
BODY_TYPE"PLUMBING"
CDS_LIB"mstr_standard";
"B \NAC \NWC"1;
"S \NAC"
BN"17"108;
%"TAP"
"6","(-5525,2400)","0","mstr_standard","I40";
;
HDL_TAP"TRUE"
BODY_TYPE"PLUMBING"
CDS_LIB"mstr_standard";
"B \NAC \NWC"1;
"S \NAC"
BN"18"109;
%"TAP"
"6","(-5525,2500)","0","mstr_standard","I41";
;
HDL_TAP"TRUE"
BODY_TYPE"PLUMBING"
CDS_LIB"mstr_standard";
"B \NAC \NWC"1;
"S \NAC"
BN"20"111;
%"TAP"
"6","(-5525,2450)","0","mstr_standard","I42";
;
HDL_TAP"TRUE"
BODY_TYPE"PLUMBING"
CDS_LIB"mstr_standard";
"B \NAC \NWC"1;
"S \NAC"
BN"19"110;
%"TAP"
"6","(-5525,2550)","0","mstr_standard","I43";
;
HDL_TAP"TRUE"
BODY_TYPE"PLUMBING"
CDS_LIB"mstr_standard";
"B \NAC \NWC"1;
"S \NAC"
BN"21"112;
%"TAP"
"6","(-5525,2600)","0","mstr_standard","I44";
;
HDL_TAP"TRUE"
BODY_TYPE"PLUMBING"
CDS_LIB"mstr_standard";
"B \NAC \NWC"1;
"S \NAC"
BN"22"113;
%"TAP"
"6","(-5525,2650)","0","mstr_standard","I45";
;
HDL_TAP"TRUE"
BODY_TYPE"PLUMBING"
CDS_LIB"mstr_standard";
"B \NAC \NWC"1;
"S \NAC"
BN"23"114;
%"TAP"
"6","(-5525,2700)","0","mstr_standard","I46";
;
HDL_TAP"TRUE"
BODY_TYPE"PLUMBING"
CDS_LIB"mstr_standard";
"B \NAC \NWC"1;
"S \NAC"
BN"24"115;
%"TAP"
"6","(-5525,2750)","0","mstr_standard","I47";
;
HDL_TAP"TRUE"
BODY_TYPE"PLUMBING"
CDS_LIB"mstr_standard";
"B \NAC \NWC"1;
"S \NAC"
BN"25"116;
%"TAP"
"6","(-5525,2800)","0","mstr_standard","I48";
;
HDL_TAP"TRUE"
BODY_TYPE"PLUMBING"
CDS_LIB"mstr_standard";
"B \NAC \NWC"1;
"S \NAC"
BN"26"117;
%"TAP"
"6","(-5525,2850)","0","mstr_standard","I49";
;
HDL_TAP"TRUE"
BODY_TYPE"PLUMBING"
CDS_LIB"mstr_standard";
"B \NAC \NWC"1;
"S \NAC"
BN"27"118;
%"TAP"
"6","(-5525,600)","0","mstr_standard","I5";
;
HDL_TAP"TRUE"
BODY_TYPE"PLUMBING"
CDS_LIB"mstr_standard";
"B \NAC \NWC"2;
"S \NAC"
BN"0"165;
%"TAP"
"6","(-5525,2900)","0","mstr_standard","I50";
;
HDL_TAP"TRUE"
BODY_TYPE"PLUMBING"
CDS_LIB"mstr_standard";
"B \NAC \NWC"1;
"S \NAC"
BN"28"119;
%"TAP"
"6","(-5525,3000)","0","mstr_standard","I51";
;
HDL_TAP"TRUE"
BODY_TYPE"PLUMBING"
CDS_LIB"mstr_standard";
"B \NAC \NWC"1;
"S \NAC"
BN"30"121;
%"TAP"
"6","(-5525,2950)","0","mstr_standard","I52";
;
HDL_TAP"TRUE"
BODY_TYPE"PLUMBING"
CDS_LIB"mstr_standard";
"B \NAC \NWC"1;
"S \NAC"
BN"29"120;
%"TAP"
"6","(-5525,3050)","0","mstr_standard","I53";
;
HDL_TAP"TRUE"
BODY_TYPE"PLUMBING"
CDS_LIB"mstr_standard";
"B \NAC \NWC"1;
"S \NAC"
BN"31"122;
%"TAP"
"6","(-5525,3100)","0","mstr_standard","I54";
;
HDL_TAP"TRUE"
BODY_TYPE"PLUMBING"
CDS_LIB"mstr_standard";
"B \NAC \NWC"1;
"S \NAC"
BN"32"123;
%"TAP"
"6","(-5525,3150)","0","mstr_standard","I55";
;
HDL_TAP"TRUE"
BODY_TYPE"PLUMBING"
CDS_LIB"mstr_standard";
"B \NAC \NWC"1;
"S \NAC"
BN"33"124;
%"TAP"
"6","(-5525,3200)","0","mstr_standard","I56";
;
HDL_TAP"TRUE"
BODY_TYPE"PLUMBING"
CDS_LIB"mstr_standard";
"B \NAC \NWC"1;
"S \NAC"
BN"34"125;
%"TAP"
"6","(-5525,3300)","0","mstr_standard","I57";
;
HDL_TAP"TRUE"
BODY_TYPE"PLUMBING"
CDS_LIB"mstr_standard";
"B \NAC \NWC"1;
"S \NAC"
BN"36"127;
%"TAP"
"6","(-5525,3250)","0","mstr_standard","I58";
;
HDL_TAP"TRUE"
BODY_TYPE"PLUMBING"
CDS_LIB"mstr_standard";
"B \NAC \NWC"1;
"S \NAC"
BN"35"126;
%"TAP"
"6","(-5525,3350)","0","mstr_standard","I59";
;
HDL_TAP"TRUE"
BODY_TYPE"PLUMBING"
CDS_LIB"mstr_standard";
"B \NAC \NWC"1;
"S \NAC"
BN"37"128;
%"TAP"
"6","(-5525,650)","0","mstr_standard","I6";
;
HDL_TAP"TRUE"
BODY_TYPE"PLUMBING"
CDS_LIB"mstr_standard";
"B \NAC \NWC"2;
"S \NAC"
BN"1"166;
%"TAP"
"6","(-5525,3400)","0","mstr_standard","I60";
;
HDL_TAP"TRUE"
BODY_TYPE"PLUMBING"
CDS_LIB"mstr_standard";
"B \NAC \NWC"1;
"S \NAC"
BN"38"129;
%"TAP"
"6","(-5525,3450)","0","mstr_standard","I61";
;
HDL_TAP"TRUE"
BODY_TYPE"PLUMBING"
CDS_LIB"mstr_standard";
"B \NAC \NWC"1;
"S \NAC"
BN"39"130;
%"TAP"
"6","(-5525,3550)","0","mstr_standard","I62";
;
HDL_TAP"TRUE"
BODY_TYPE"PLUMBING"
CDS_LIB"mstr_standard";
"B \NAC \NWC"1;
"S \NAC"
BN"41"132;
%"TAP"
"6","(-5525,3500)","0","mstr_standard","I63";
;
HDL_TAP"TRUE"
BODY_TYPE"PLUMBING"
CDS_LIB"mstr_standard";
"B \NAC \NWC"1;
"S \NAC"
BN"40"131;
%"TAP"
"6","(-5525,3600)","0","mstr_standard","I64";
;
HDL_TAP"TRUE"
BODY_TYPE"PLUMBING"
CDS_LIB"mstr_standard";
"B \NAC \NWC"1;
"S \NAC"
BN"42"133;
%"TAP"
"6","(-5525,3650)","0","mstr_standard","I65";
;
HDL_TAP"TRUE"
BODY_TYPE"PLUMBING"
CDS_LIB"mstr_standard";
"B \NAC \NWC"1;
"S \NAC"
BN"43"134;
%"TAP"
"6","(-5525,3700)","0","mstr_standard","I66";
;
HDL_TAP"TRUE"
BODY_TYPE"PLUMBING"
CDS_LIB"mstr_standard";
"B \NAC \NWC"1;
"S \NAC"
BN"44"135;
%"TAP"
"6","(-5525,3750)","0","mstr_standard","I67";
;
HDL_TAP"TRUE"
BODY_TYPE"PLUMBING"
CDS_LIB"mstr_standard";
"B \NAC \NWC"1;
"S \NAC"
BN"45"136;
%"TAP"
"6","(-5525,3800)","0","mstr_standard","I68";
;
HDL_TAP"TRUE"
BODY_TYPE"PLUMBING"
CDS_LIB"mstr_standard";
"B \NAC \NWC"1;
"S \NAC"
BN"46"137;
%"TAP"
"6","(-5525,3850)","0","mstr_standard","I69";
;
HDL_TAP"TRUE"
BODY_TYPE"PLUMBING"
CDS_LIB"mstr_standard";
"B \NAC \NWC"1;
"S \NAC"
BN"47"138;
%"TAP"
"6","(-5525,700)","0","mstr_standard","I7";
;
HDL_TAP"TRUE"
BODY_TYPE"PLUMBING"
CDS_LIB"mstr_standard";
"B \NAC \NWC"2;
"S \NAC"
BN"2"167;
%"TAP"
"6","(-5525,3900)","0","mstr_standard","I70";
;
HDL_TAP"TRUE"
BODY_TYPE"PLUMBING"
CDS_LIB"mstr_standard";
"B \NAC \NWC"1;
"S \NAC"
BN"48"139;
%"TAP"
"6","(-5525,3950)","0","mstr_standard","I71";
;
HDL_TAP"TRUE"
BODY_TYPE"PLUMBING"
CDS_LIB"mstr_standard";
"B \NAC \NWC"1;
"S \NAC"
BN"49"140;
%"TAP"
"6","(-5525,4050)","0","mstr_standard","I73";
;
HDL_TAP"TRUE"
BODY_TYPE"PLUMBING"
CDS_LIB"mstr_standard";
"B \NAC \NWC"1;
"S \NAC"
BN"51"142;
%"TAP"
"6","(-5525,4000)","0","mstr_standard","I74";
;
HDL_TAP"TRUE"
BODY_TYPE"PLUMBING"
CDS_LIB"mstr_standard";
"B \NAC \NWC"1;
"S \NAC"
BN"50"141;
%"TAP"
"6","(-5525,4150)","0","mstr_standard","I75";
;
HDL_TAP"TRUE"
BODY_TYPE"PLUMBING"
CDS_LIB"mstr_standard";
"B \NAC \NWC"1;
"S \NAC"
BN"53"91;
%"TAP"
"6","(-5525,4200)","0","mstr_standard","I76";
;
HDL_TAP"TRUE"
BODY_TYPE"PLUMBING"
CDS_LIB"mstr_standard";
"B \NAC \NWC"1;
"S \NAC"
BN"54"92;
%"TAP"
"6","(-5525,4100)","0","mstr_standard","I77";
;
HDL_TAP"TRUE"
BODY_TYPE"PLUMBING"
CDS_LIB"mstr_standard";
"B \NAC \NWC"1;
"S \NAC"
BN"52"90;
%"TAP"
"6","(-5525,4250)","0","mstr_standard","I78";
;
HDL_TAP"TRUE"
BODY_TYPE"PLUMBING"
CDS_LIB"mstr_standard";
"B \NAC \NWC"1;
"S \NAC"
BN"55"93;
%"TAP"
"6","(-5525,4300)","0","mstr_standard","I79";
;
HDL_TAP"TRUE"
BODY_TYPE"PLUMBING"
CDS_LIB"mstr_standard";
"B \NAC \NWC"1;
"S \NAC"
BN"56"94;
%"TAP"
"6","(-5525,800)","0","mstr_standard","I8";
;
HDL_TAP"TRUE"
BODY_TYPE"PLUMBING"
CDS_LIB"mstr_standard";
"B \NAC \NWC"3;
"S \NAC"
BN"0"161;
%"TAP"
"6","(-5525,4350)","0","mstr_standard","I80";
;
HDL_TAP"TRUE"
BODY_TYPE"PLUMBING"
CDS_LIB"mstr_standard";
"B \NAC \NWC"1;
"S \NAC"
BN"57"95;
%"TAP"
"6","(-5525,4400)","0","mstr_standard","I81";
;
HDL_TAP"TRUE"
BODY_TYPE"PLUMBING"
CDS_LIB"mstr_standard";
"B \NAC \NWC"1;
"S \NAC"
BN"58"96;
%"TAP"
"6","(-5525,4450)","0","mstr_standard","I82";
;
HDL_TAP"TRUE"
BODY_TYPE"PLUMBING"
CDS_LIB"mstr_standard";
"B \NAC \NWC"1;
"S \NAC"
BN"59"97;
%"TAP"
"6","(-5525,4500)","0","mstr_standard","I83";
;
HDL_TAP"TRUE"
BODY_TYPE"PLUMBING"
CDS_LIB"mstr_standard";
"B \NAC \NWC"1;
"S \NAC"
BN"60"98;
%"TAP"
"6","(-5525,4550)","0","mstr_standard","I84";
;
HDL_TAP"TRUE"
BODY_TYPE"PLUMBING"
CDS_LIB"mstr_standard";
"B \NAC \NWC"1;
"S \NAC"
BN"61"99;
%"TAP"
"6","(-5525,4650)","0","mstr_standard","I85";
;
HDL_TAP"TRUE"
BODY_TYPE"PLUMBING"
CDS_LIB"mstr_standard";
"B \NAC \NWC"1;
"S \NAC"
BN"63"101;
%"TAP"
"6","(-5525,4600)","0","mstr_standard","I86";
;
HDL_TAP"TRUE"
BODY_TYPE"PLUMBING"
CDS_LIB"mstr_standard";
"B \NAC \NWC"1;
"S \NAC"
BN"62"100;
%"TAP"
"6","(-2800,800)","2","mstr_standard","I87";
;
HDL_TAP"TRUE"
BODY_TYPE"PLUMBING"
CDS_LIB"mstr_standard";
"B \NAC \NWC"6;
"S \NAC"
BN"0"86;
%"TAP"
"6","(-2800,850)","2","mstr_standard","I88";
;
HDL_TAP"TRUE"
BODY_TYPE"PLUMBING"
CDS_LIB"mstr_standard";
"B \NAC \NWC"6;
"S \NAC"
BN"1"87;
%"TAP"
"6","(-2800,750)","2","mstr_standard","I89";
;
HDL_TAP"TRUE"
BODY_TYPE"PLUMBING"
CDS_LIB"mstr_standard";
"B \NAC \NWC"5;
"S \NAC"
BN"1"89;
%"TAP"
"6","(-5525,850)","0","mstr_standard","I9";
;
HDL_TAP"TRUE"
BODY_TYPE"PLUMBING"
CDS_LIB"mstr_standard";
"B \NAC \NWC"3;
"S \NAC"
BN"1"162;
%"TAP"
"6","(-2800,700)","2","mstr_standard","I90";
;
HDL_TAP"TRUE"
BODY_TYPE"PLUMBING"
CDS_LIB"mstr_standard";
"B \NAC \NWC"5;
"S \NAC"
BN"0"88;
%"TAP"
"6","(-2800,950)","2","mstr_standard","I91";
;
HDL_TAP"TRUE"
BODY_TYPE"PLUMBING"
CDS_LIB"mstr_standard";
"B \NAC \NWC"8;
"S \NAC"
BN"0"74;
%"TAP"
"6","(-2800,1150)","2","mstr_standard","I92";
;
HDL_TAP"TRUE"
BODY_TYPE"PLUMBING"
CDS_LIB"mstr_standard";
"B \NAC \NWC"8;
"S \NAC"
BN"4"78;
%"TAP"
"6","(-2800,1100)","2","mstr_standard","I93";
;
HDL_TAP"TRUE"
BODY_TYPE"PLUMBING"
CDS_LIB"mstr_standard";
"B \NAC \NWC"8;
"S \NAC"
BN"3"77;
%"TAP"
"6","(-2800,1050)","2","mstr_standard","I94";
;
HDL_TAP"TRUE"
BODY_TYPE"PLUMBING"
CDS_LIB"mstr_standard";
"B \NAC \NWC"8;
"S \NAC"
BN"2"76;
%"TAP"
"6","(-2800,1000)","2","mstr_standard","I95";
;
HDL_TAP"TRUE"
BODY_TYPE"PLUMBING"
CDS_LIB"mstr_standard";
"B \NAC \NWC"8;
"S \NAC"
BN"1"75;
%"TAP"
"6","(-2800,1400)","2","mstr_standard","I96";
;
HDL_TAP"TRUE"
BODY_TYPE"PLUMBING"
CDS_LIB"mstr_standard";
"B \NAC \NWC"10;
"S \NAC"
BN"0"67;
%"TAP"
"6","(-2800,1250)","2","mstr_standard","I97";
;
HDL_TAP"TRUE"
BODY_TYPE"PLUMBING"
CDS_LIB"mstr_standard";
"B \NAC \NWC"8;
"S \NAC"
BN"6"80;
%"TAP"
"6","(-2800,1200)","2","mstr_standard","I98";
;
HDL_TAP"TRUE"
BODY_TYPE"PLUMBING"
CDS_LIB"mstr_standard";
"B \NAC \NWC"8;
"S \NAC"
BN"5"79;
%"TAP"
"6","(-2800,1300)","2","mstr_standard","I99";
;
HDL_TAP"TRUE"
BODY_TYPE"PLUMBING"
CDS_LIB"mstr_standard";
"B \NAC \NWC"8;
"S \NAC"
BN"7"81;
END.
